;LEADER: 12 
;HEADER: 
;CODE  : ASCII 
;FILE  : 9332_F0TG_MB_C_V02_0417_0820-bd-18-17.drl for backdrilling ... from layer BOTTOM to layer GND7
;DESIGN: 9332_F0TG_MB_C_V02_0417_0820.brd
;MUST-NOT-CUT-LAYER = IN6,  MAX_DRILL_DEPTH = 8.90 MILS,  MFG_STUB_LENGTH = 0.00 MILS
;   BackdrillSize 1. = 14.800000 Tolerance = +0.000000/-0.000000 NON_PLATED MILS Quantity = 132
;   BackdrillSize 2. = 17.000000 Tolerance = +0.000000/-0.000000 NON_PLATED MILS Quantity = 192
;   BackdrillSize 3. = 21.170000 Tolerance = +0.000000/-0.000000 NON_PLATED MILS Quantity = 128
%
G90
X1456909Y0886001
X1460609Y0886001
X1464310Y0879623
X1460609Y0879623
X0422760Y1069513
X0232249Y1519698
X0411658Y1063135
X0227525Y1519698
X0432012Y1059946
X0260596Y1519698
X0432012Y1066324
X0255871Y1519698
X0432012Y1079080
X0251147Y1519698
X0432012Y1072702
X0246422Y1519698
X0422760Y1063135
X0241698Y1519698
X0422760Y1075891
X0236974Y1519698
X0419059Y1069513
X0230674Y1516970
X0407957Y1063135
X0225950Y1516970
X0428311Y1059946
X0259021Y1516970
X0428311Y1066324
X0254297Y1516970
X0428311Y1079080
X0249572Y1516970
X0428311Y1072702
X0244848Y1516970
X0419059Y1063135
X0240123Y1516970
X0419059Y1075891
X0235399Y1516970
X1398902Y1069512
X1240122Y1552698
X1387800Y1063134
X1235398Y1552698
X1408154Y1059945
X1268469Y1552698
X1408154Y1066323
X1263744Y1552698
X1408154Y1079079
X1259020Y1552698
X1408154Y1072701
X1254295Y1552698
X1398902Y1063134
X1249571Y1552698
X1398902Y1075890
X1244847Y1552698
X1395201Y1069512
X1238547Y1549970
X1384099Y1063134
X1233823Y1549970
X1404453Y1059945
X1266894Y1549970
X1404453Y1066323
X1262170Y1549970
X1404453Y1079079
X1257445Y1549970
X1404453Y1072701
X1252721Y1549970
X1395201Y1063134
X1247996Y1549970
X1395201Y1075890
X1243272Y1549970
X0469664Y0968915
X1386619Y0968914
X0469664Y0962537
X1386619Y0962536
X0469664Y0975293
X1386619Y0975292
X0458562Y0968915
X1397721Y0968914
X0458562Y0962537
X1397721Y0962536
X0458562Y0975293
X1397721Y0975292
X0449310Y0965726
X1406973Y0965725
X0449310Y0959348
X1406973Y0959347
X0449310Y0972104
X1406973Y0972103
X0491869Y0968915
X1364414Y0968914
X0491869Y0962537
X1364414Y0962536
X0491869Y0975293
X1364414Y0975292
X0480767Y0968915
X1375516Y0968914
X0480767Y0962537
X1375516Y0962536
X0480767Y0975293
X1375516Y0975292
X0449310Y0978482
X1406973Y0978481
X0473365Y0968915
X1382918Y0968914
X0473365Y0962537
X1382918Y0962536
X0473365Y0975293
X1382918Y0975292
X0462263Y0968915
X1394020Y0968914
X0462263Y0962537
X1394020Y0962536
X0462263Y0975293
X1394020Y0975292
X0453011Y0965726
X1403272Y0965725
X0453011Y0959348
X1403272Y0959347
X0453011Y0972104
X1403272Y0972103
X0495570Y0968915
X1360713Y0968914
X0495570Y0962537
X1360713Y0962536
X0495570Y0975293
X1360713Y0975292
X0484467Y0968915
X1371815Y0968914
X0484467Y0962537
X1371815Y0962536
X0484467Y0975293
X1371815Y0975292
X0453011Y0978482
X1403272Y0978481
M00
X0623009Y1548397
X0618285Y1548397
X0613560Y1548397
X0608836Y1548397
X0604111Y1548397
X0599387Y1548397
X0594662Y1548397
X0589938Y1548397
X0585213Y1548397
X0651355Y1548397
X0646631Y1548397
X0641906Y1548397
X0637182Y1548397
R02X-0004724
X0580489Y1548397
X0623009Y1544997
X0618285Y1544997
X0613560Y1544997
X0608836Y1544997
X0604111Y1544997
X0599387Y1544997
X0594662Y1544997
X0589938Y1544997
X0585213Y1544997
X0651355Y1544997
X0646631Y1544997
X0641906Y1544997
X0637182Y1544997
R02X-0004724
X0580489Y1544997
X0230774Y1548397
X0226050Y1548397
X0221325Y1548397
X0216601Y1548397
X0211876Y1548397
X0207152Y1548397
X0202427Y1548397
X0197703Y1548397
X0192978Y1548397
X0259120Y1548397
X0254396Y1548397
X0249671Y1548397
X0244947Y1548397
R02X-0004724
X0188254Y1548397
X0230774Y1544997
X0226050Y1544997
X0221325Y1544997
X0216601Y1544997
X0211876Y1544997
X0207152Y1544997
X0202427Y1544997
X0197703Y1544997
X0192978Y1544997
X0259120Y1544997
X0254396Y1544997
X0249671Y1544997
X0244947Y1544997
R02X-0004724
X0188254Y1544997
X1630883Y1581397
X1626159Y1581397
X1621434Y1581397
X1616710Y1581397
X1611985Y1581397
X1607261Y1581397
X1602536Y1581397
X1597812Y1581397
X1593087Y1581397
X1659229Y1581397
X1654505Y1581397
X1649780Y1581397
X1645056Y1581397
R02X-0004724
X1588363Y1581397
X1630883Y1577997
X1626159Y1577997
X1621434Y1577997
X1616710Y1577997
X1611985Y1577997
X1607261Y1577997
X1602536Y1577997
X1597812Y1577997
X1593087Y1577997
X1659229Y1577997
X1654505Y1577997
X1649780Y1577997
X1645056Y1577997
R02X-0004724
X1588363Y1577997
X1238647Y1581397
X1233923Y1581397
X1229198Y1581397
X1224474Y1581397
X1219749Y1581397
X1215025Y1581397
X1210300Y1581397
X1205576Y1581397
X1200851Y1581397
X1266993Y1581397
X1262269Y1581397
X1257544Y1581397
X1252820Y1581397
R02X-0004724
X1196127Y1581397
X1238647Y1577997
X1233923Y1577997
X1229198Y1577997
X1224474Y1577997
X1219749Y1577997
X1215025Y1577997
X1210300Y1577997
X1205576Y1577997
X1200851Y1577997
X1266993Y1577997
X1262269Y1577997
X1257544Y1577997
X1252820Y1577997
R02X-0004724
X1196127Y1577997
X0553780Y0121240
X0553780Y0124640
X0099443Y1658531
X0041679Y1676723
X0099443Y1661931
X0041679Y1673323
X0100443Y1687463
X0040922Y1658269
X0100443Y1684063
X0040922Y1654869
X0570860Y0124710
X0570860Y0121310
X0482380Y0141942
X0540615Y0088213
X0485780Y0141942
X0538210Y0090618
X1007587Y0764946
X1007587Y0775880
X1007587Y0786882
X1007587Y0797884
X1007587Y0761546
X1007587Y0772480
X1007587Y0783482
X1007587Y0794484
X0062813Y0416000
X0558576Y0071436
X0062812Y0412100
X0555176Y0071436
X0157511Y1663933
X0523143Y0071436
X0154111Y1663933
X0519743Y0071436
X0157410Y1676811
X0523165Y0040328
X0154010Y1676811
X0519765Y0040328
X0080318Y0539413
X0080318Y0543313
X0388630Y1236747
X0390974Y1219449
X0368726Y1214455
X0313284Y1215122
X0388630Y1240147
X0390974Y1222849
X0372126Y1214455
X0313284Y1218522
X1370685Y1223032
X1346063Y1214329
X1342036Y1203029
X1315657Y1196132
X1370685Y1226432
X1346063Y1217729
X1342036Y1206429
X1315657Y1199532
X0193679Y1640052
X0193679Y1643452
X0035852Y0699822
R02Y-0010906
X0035852Y0667045
X0035852Y0703222
X0035852Y0692316
X0035852Y0681410
X0035852Y0670445
M00
X0337205Y1728700
X0352953Y1728700
X0329331Y1724763
X0337205Y1723976
X0345079Y1724763
X0352953Y1723976
X0329331Y1720039
X0345079Y1720039
X0305709Y1728700
X0321457Y1728700
X0297835Y1724763
X0305709Y1723976
X0313583Y1724763
X0321457Y1723976
X0297835Y1720039
X0313583Y1720039
X0270275Y1728700
X0286023Y1728700
X0262401Y1724763
X0270275Y1723976
X0278149Y1724763
X0286023Y1723976
X0262401Y1720039
X0278149Y1720039
X0238779Y1728700
X0254527Y1728700
X0230905Y1724763
X0238779Y1723976
X0246653Y1724763
X0254527Y1723976
X0230905Y1720039
X0246653Y1720039
X0534448Y1728700
X0550196Y1728700
X0526574Y1724763
X0534448Y1723976
X0542322Y1724763
X0550196Y1723976
X0526574Y1720039
X0542322Y1720039
X0502952Y1728700
X0518700Y1728700
X0495078Y1724763
X0502952Y1723976
X0510826Y1724763
X0518700Y1723976
X0495078Y1720039
X0510826Y1720039
X0601378Y1728700
X0617126Y1728700
X0593504Y1724763
X0601378Y1723976
X0609252Y1724763
X0617126Y1723976
X0593504Y1720039
X0609252Y1720039
X0569882Y1728700
X0585630Y1728700
X0562008Y1724763
X0569882Y1723976
X0577756Y1724763
X0585630Y1723976
X0562008Y1720039
X0577756Y1720039
X1345078Y1728700
X1360826Y1728700
X1337204Y1724763
X1345078Y1723976
X1352952Y1724763
X1360826Y1723976
X1337204Y1720039
X1352952Y1720039
X1313582Y1728700
X1329330Y1728700
X1305708Y1724763
X1313582Y1723976
X1321456Y1724763
X1329330Y1723976
X1305708Y1720039
X1321456Y1720039
X1278148Y1728700
X1293896Y1728700
X1270274Y1724763
X1278148Y1723976
X1286022Y1724763
X1293896Y1723976
X1270274Y1720039
X1286022Y1720039
X1246652Y1728700
X1262400Y1728700
X1238778Y1724763
X1246652Y1723976
X1254526Y1724763
X1262400Y1723976
X1238778Y1720039
X1254526Y1720039
X1542322Y1728700
X1558070Y1728700
X1534448Y1724763
X1542322Y1723976
X1550196Y1724763
X1558070Y1723976
X1534448Y1720039
X1550196Y1720039
X1510826Y1728700
X1526574Y1728700
X1502952Y1724763
X1510826Y1723976
X1518700Y1724763
X1526574Y1723976
X1502952Y1720039
X1518700Y1720039
X1609252Y1728700
X1625000Y1728700
X1601378Y1724763
X1609252Y1723976
X1617126Y1724763
X1625000Y1723976
X1601378Y1720039
X1617126Y1720039
X1577756Y1728700
X1593504Y1728700
X1569882Y1724763
X1577756Y1723976
X1585630Y1724763
X1593504Y1723976
X1569882Y1720039
X1585630Y1720039
M30
